(kicad_pcb
	(version 20260206)
	(generator "pcbnew")
	(generator_version "10.0")
	(general
		(thickness 1.6)
		(legacy_teardrops no)
	)
	(paper "A4")
	(title_block
		(title "fcb — Lightning_FCB_BRD.brd")
		(comment 1 "Lightning (Wiwynn / Facebook NVMe JBOF) / footprints 46-52 of 495")
	)
	(layers
		(0 "F.Cu" signal "TOP")
		(4 "In1.Cu" signal "L2GND")
		(6 "In2.Cu" signal "L3VCC")
		(2 "B.Cu" signal "BOTTOM")
		(9 "F.Adhes" user "F.Adhesive")
		(11 "B.Adhes" user "B.Adhesive")
		(13 "F.Paste" user "Package Geometry/Pastemask Top")
		(15 "B.Paste" user "Package Geometry/Pastemask Bottom")
		(5 "F.SilkS" user "Ref Des/Silkscreen Top")
		(7 "B.SilkS" user "Ref Des/Silkscreen Bottom")
		(1 "F.Mask" user "Board Geometry/Soldermask Top")
		(3 "B.Mask" user "Board Geometry/Soldermask Bottom")
		(17 "Dwgs.User" user "User.Drawings")
		(19 "Cmts.User" user "User.Comments")
		(21 "Eco1.User" user "User.Eco1")
		(23 "Eco2.User" user "User.Eco2")
		(25 "Edge.Cuts" user "Board Geometry/Outline")
		(27 "Margin" user)
		(31 "F.CrtYd" user "Package Geometry/Place Bound Top")
		(29 "B.CrtYd" user "Package Geometry/Place Bound Bottom")
		(35 "F.Fab" user "Ref Des/Assembly Top")
		(33 "B.Fab" user "Ref Des/Assembly Bottom")
	)
	(footprint ""
		(layer "F.Cu")
		(at 23.876 -243.84 180)
		(property "Reference" "PR54"
			(at 0 0 180)
			(layer "F.SilkS")
			(hide yes)
			(effects
				(font
					(size 1.27 1.27)
				)
			)
		)
		(property "Value" "0R3J-0-U-GP"
			(at -0.0254 -2.5146 180)
			(unlocked yes)
			(layer "F.Fab")
			(hide yes)
			(effects
				(font
					(size 1.016 1.016)
					(thickness 0.1524)
				)
			)
		)
		(property "Device Type" "R603H22"
			(at -0.0254 -4.0386 180)
			(unlocked yes)
			(layer "F.Fab")
			(hide yes)
			(effects
				(font
					(size 1.016 1.016)
					(thickness 0.1524)
				)
			)
		)
		(duplicate_pad_numbers_are_jumpers no)
		(fp_line
			(start 0.2032 0)
			(end 0.4826 0)
			(stroke
				(width 0.2032)
				(type default)
			)
			(layer "F.SilkS")
		)
		(fp_line
			(start -0.4826 0)
			(end -0.2032 0)
			(stroke
				(width 0.2032)
				(type default)
			)
			(layer "F.SilkS")
		)
		(fp_rect
			(start -0.5842 1.3335)
			(end 0.5842 -1.3335)
			(stroke
				(width 0)
				(type default)
			)
			(fill no)
			(layer "F.CrtYd")
		)
		(fp_rect
			(start -0.5842 1.3335)
			(end 0.5842 -1.3335)
			(stroke
				(width 0)
				(type default)
			)
			(fill no)
			(layer "F.Fab")
		)
		(pad "1" smd custom
			(at 0 -0.762 180)
			(size 0.2159 0.2159)
			(layers "F.Cu" "F.Mask" "F.Paste")
			(net "P3V3_LX_COPPER")
			(options
				(clearance outline)
				(anchor circle)
			)
			(primitives
				(gr_poly
					(pts
						(arc
							(start -0.3302 -0.4318)
							(mid -0.402042 -0.402042)
							(end -0.4318 -0.3302)
						)
						(arc
							(start -0.4318 0.3302)
							(mid -0.402042 0.402042)
							(end -0.3302 0.4318)
						)
						(arc
							(start 0.3302 0.4318)
							(mid 0.402042 0.402042)
							(end 0.4318 0.3302)
						)
						(arc
							(start 0.4318 -0.3302)
							(mid 0.402042 -0.402042)
							(end 0.3302 -0.4318)
						)
					)
					(width 0)
					(fill yes)
				)
			)
		)
		(pad "2" smd custom
			(at 0 0.762 180)
			(size 0.2159 0.2159)
			(layers "F.Cu" "F.Mask" "F.Paste")
			(net "P3V3_LX_REV")
			(options
				(clearance outline)
				(anchor circle)
			)
			(primitives
				(gr_poly
					(pts
						(arc
							(start -0.3302 -0.4318)
							(mid -0.402042 -0.402042)
							(end -0.4318 -0.3302)
						)
						(arc
							(start -0.4318 0.3302)
							(mid -0.402042 0.402042)
							(end -0.3302 0.4318)
						)
						(arc
							(start 0.3302 0.4318)
							(mid 0.402042 0.402042)
							(end 0.4318 0.3302)
						)
						(arc
							(start 0.4318 -0.3302)
							(mid 0.402042 -0.402042)
							(end 0.3302 -0.4318)
						)
					)
					(width 0)
					(fill yes)
				)
			)
		)
	)
	(footprint ""
		(layer "F.Cu")
		(at 26.6954 -289.433)
		(property "Reference" "R178"
			(at 0 0 0)
			(layer "F.SilkS")
			(hide yes)
			(effects
				(font
					(size 1.27 1.27)
				)
			)
		)
		(property "Value" "0R1206-PAD-1-GP"
			(at 0 -5.0292 0)
			(unlocked yes)
			(layer "F.Fab")
			(hide yes)
			(effects
				(font
					(size 1.016 1.016)
					(thickness 0.1524)
				)
			)
		)
		(property "Device Type" "0R1206-PAD-1"
			(at 0 -6.5532 0)
			(unlocked yes)
			(layer "F.Fab")
			(hide yes)
			(effects
				(font
					(size 1.016 1.016)
					(thickness 0.1524)
				)
			)
		)
		(duplicate_pad_numbers_are_jumpers no)
		(fp_line
			(start -1.016 -2.2352)
			(end -1.016 2.2352)
			(stroke
				(width 0.1524)
				(type default)
			)
			(layer "F.SilkS")
		)
		(fp_line
			(start -1.016 2.2352)
			(end 1.016 2.2352)
			(stroke
				(width 0.1524)
				(type default)
			)
			(layer "F.SilkS")
		)
		(fp_line
			(start 1.016 -2.2352)
			(end -1.016 -2.2352)
			(stroke
				(width 0.1524)
				(type default)
			)
			(layer "F.SilkS")
		)
		(fp_line
			(start 1.016 2.2352)
			(end 1.016 -2.2352)
			(stroke
				(width 0.1524)
				(type default)
			)
			(layer "F.SilkS")
		)
		(fp_rect
			(start -1.0922 2.3114)
			(end 1.0922 -2.3114)
			(stroke
				(width 0)
				(type default)
			)
			(fill no)
			(layer "F.CrtYd")
		)
		(fp_poly
			(pts
				(xy -1.0922 -2.3114) (xy 1.0922 -2.3114) (xy 1.0922 2.3114) (xy -1.0922 2.3114)
			)
			(stroke
				(width 0)
				(type default)
			)
			(fill no)
			(layer "F.Fab")
		)
		(pad "1" smd rect
			(at 0 -1.397)
			(size 1.651 2.0574)
			(drill
				(offset 0 0.3937)
			)
			(layers "F.Cu" "F.Mask" "F.Paste")
			(net "P12V_FAN2")
		)
		(pad "2" smd rect
			(at 0 1.397)
			(size 1.651 2.0574)
			(drill
				(offset 0 -0.3937)
			)
			(layers "F.Cu" "F.Mask" "F.Paste")
			(net "P12V")
		)
	)
	(footprint ""
		(layer "F.Cu")
		(at 16.2052 -249.1994 180)
		(property "Reference" "PC40"
			(at 0 0 180)
			(layer "F.SilkS")
			(hide yes)
			(effects
				(font
					(size 1.27 1.27)
				)
			)
		)
		(property "Value" "SC4D7U50V6KX-L2-GP"
			(at 0 -6.8072 180)
			(unlocked yes)
			(layer "F.Fab")
			(hide yes)
			(effects
				(font
					(size 1.016 1.016)
					(thickness 0.1524)
				)
			)
		)
		(property "Device Type" "C1206H38"
			(at 0 -8.7122 180)
			(unlocked yes)
			(layer "F.Fab")
			(hide yes)
			(effects
				(font
					(size 1.016 1.016)
					(thickness 0.1524)
				)
			)
		)
		(duplicate_pad_numbers_are_jumpers no)
		(fp_line
			(start 1.016 2.2352)
			(end -1.016 2.2352)
			(stroke
				(width 0.1524)
				(type default)
			)
			(layer "F.SilkS")
		)
		(fp_line
			(start 1.016 0.8382)
			(end 1.016 2.2352)
			(stroke
				(width 0.1524)
				(type default)
			)
			(layer "F.SilkS")
		)
		(fp_line
			(start 1.016 -2.2352)
			(end 1.016 -0.8382)
			(stroke
				(width 0.1524)
				(type default)
			)
			(layer "F.SilkS")
		)
		(fp_line
			(start 1.016 -2.2352)
			(end -1.016 -2.2352)
			(stroke
				(width 0.1524)
				(type default)
			)
			(layer "F.SilkS")
		)
		(fp_line
			(start -1.016 2.2352)
			(end -1.016 0.8128)
			(stroke
				(width 0.1524)
				(type default)
			)
			(layer "F.SilkS")
		)
		(fp_line
			(start -1.016 -2.2352)
			(end -1.016 -0.8382)
			(stroke
				(width 0.1524)
				(type default)
			)
			(layer "F.SilkS")
		)
		(fp_rect
			(start -1.0922 2.3114)
			(end 1.0922 -2.3114)
			(stroke
				(width 0)
				(type default)
			)
			(fill no)
			(layer "F.CrtYd")
		)
		(fp_poly
			(pts
				(xy -1.0922 -2.3114) (xy 1.0922 -2.3114) (xy 1.0922 2.3114) (xy -1.0922 2.3114)
			)
			(stroke
				(width 0)
				(type default)
			)
			(fill no)
			(layer "F.Fab")
		)
		(pad "1" smd rect
			(at 0 -1.397 180)
			(size 1.651 1.27)
			(layers "F.Cu" "F.Mask" "F.Paste")
			(net "P3V3_IN")
		)
		(pad "2" smd rect
			(at 0 1.397 180)
			(size 1.651 1.27)
			(layers "F.Cu" "F.Mask" "F.Paste")
			(net "GND")
		)
	)
	(footprint ""
		(layer "F.Cu")
		(at 15.9258 -145.542 -90)
		(property "Reference" "C30"
			(at 0 0 270)
			(layer "F.SilkS")
			(hide yes)
			(effects
				(font
					(size 1.27 1.27)
				)
			)
		)
		(property "Value" "SCD1U16V2KX-3GP"
			(at 1.1811 -2.7051 270)
			(unlocked yes)
			(layer "F.Fab")
			(hide yes)
			(effects
				(font
					(size 1.016 1.016)
					(thickness 0.1524)
				)
			)
		)
		(property "Device Type" "C402H22"
			(at 1.1811 -4.2291 270)
			(unlocked yes)
			(layer "F.Fab")
			(hide yes)
			(effects
				(font
					(size 1.016 1.016)
					(thickness 0.1524)
				)
			)
		)
		(duplicate_pad_numbers_are_jumpers no)
		(fp_rect
			(start -0.4318 0.9525)
			(end 0.4318 -0.9525)
			(stroke
				(width 0)
				(type default)
			)
			(fill no)
			(layer "F.CrtYd")
		)
		(fp_rect
			(start -0.4318 0.9525)
			(end 0.4318 -0.9525)
			(stroke
				(width 0)
				(type default)
			)
			(fill no)
			(layer "F.Fab")
		)
		(pad "1" smd custom
			(at 0 -0.4445 270)
			(size 0.1524 0.1524)
			(layers "F.Cu" "F.Mask" "F.Paste")
			(net "FAN_TACH9")
			(options
				(clearance outline)
				(anchor circle)
			)
			(primitives
				(gr_poly
					(pts
						(arc
							(start 0.3048 -0.2032)
							(mid 0.275042 -0.275042)
							(end 0.2032 -0.3048)
						)
						(arc
							(start -0.2032 -0.3048)
							(mid -0.275042 -0.275042)
							(end -0.3048 -0.2032)
						)
						(arc
							(start -0.3048 0.2032)
							(mid -0.275042 0.275042)
							(end -0.2032 0.3048)
						)
						(arc
							(start 0.2032 0.3048)
							(mid 0.275042 0.275042)
							(end 0.3048 0.2032)
						)
					)
					(width 0)
					(fill yes)
				)
			)
		)
		(pad "2" smd custom
			(at 0 0.4445 270)
			(size 0.1524 0.1524)
			(layers "F.Cu" "F.Mask" "F.Paste")
			(net "GND")
			(options
				(clearance outline)
				(anchor circle)
			)
			(primitives
				(gr_poly
					(pts
						(arc
							(start 0.3048 -0.2032)
							(mid 0.275042 -0.275042)
							(end 0.2032 -0.3048)
						)
						(arc
							(start -0.2032 -0.3048)
							(mid -0.275042 -0.275042)
							(end -0.3048 -0.2032)
						)
						(arc
							(start -0.3048 0.2032)
							(mid -0.275042 0.275042)
							(end -0.2032 0.3048)
						)
						(arc
							(start 0.2032 0.3048)
							(mid 0.275042 0.275042)
							(end 0.3048 0.2032)
						)
					)
					(width 0)
					(fill yes)
				)
			)
		)
	)
	(footprint ""
		(layer "F.Cu")
		(at 43.18 -400.177)
		(property "Reference" "PQ3"
			(at 0 0 0)
			(layer "F.SilkS")
			(hide yes)
			(effects
				(font
					(size 1.27 1.27)
				)
			)
		)
		(property "Value" "PH0925CL-GP"
			(at -4.2799 -0.4572 0)
			(unlocked yes)
			(layer "F.Fab")
			(hide yes)
			(effects
				(font
					(size 1.016 1.016)
					(thickness 0.1524)
				)
			)
		)
		(property "Device Type" "LFPAK-5PH48-U"
			(at -4.2799 -1.9812 0)
			(unlocked yes)
			(layer "F.Fab")
			(hide yes)
			(effects
				(font
					(size 1.016 1.016)
					(thickness 0.1524)
				)
			)
		)
		(duplicate_pad_numbers_are_jumpers no)
		(fp_line
			(start -2.7559 -6.5532)
			(end -2.7559 1.0668)
			(stroke
				(width 0.1524)
				(type default)
			)
			(layer "F.SilkS")
		)
		(fp_line
			(start -2.7559 1.0668)
			(end 2.7559 1.0668)
			(stroke
				(width 0.1524)
				(type default)
			)
			(layer "F.SilkS")
		)
		(fp_line
			(start -1.7272 1.1684)
			(end -2.1082 1.1684)
			(stroke
				(width 0.3302)
				(type default)
			)
			(layer "F.SilkS")
		)
		(fp_line
			(start 2.7559 -6.5532)
			(end -2.7559 -6.5532)
			(stroke
				(width 0.1524)
				(type default)
			)
			(layer "F.SilkS")
		)
		(fp_line
			(start 2.7559 1.0668)
			(end 2.7559 -6.5532)
			(stroke
				(width 0.1524)
				(type default)
			)
			(layer "F.SilkS")
		)
		(fp_poly
			(pts
				(xy -2.3368 1.5748) (xy -1.905 1.143) (xy -1.4732 1.5748)
			)
			(stroke
				(width 0)
				(type default)
			)
			(fill yes)
			(layer "F.SilkS")
		)
		(fp_poly
			(pts
				(xy -2.5019 -4.02971) (xy -0.3302 -4.02971) (xy -0.3302 -6.30301) (xy -2.5019 -6.30301)
			)
			(stroke
				(width 0)
				(type default)
			)
			(fill yes)
			(layer "F.Paste")
		)
		(fp_poly
			(pts
				(xy -2.5019 -1.09601) (xy -0.3302 -1.09601) (xy -0.3302 -3.36931) (xy -2.5019 -3.36931)
			)
			(stroke
				(width 0)
				(type default)
			)
			(fill yes)
			(layer "F.Paste")
		)
		(fp_poly
			(pts
				(xy 0.3302 -4.02971) (xy 2.5019 -4.02971) (xy 2.5019 -6.30301) (xy 0.3302 -6.30301)
			)
			(stroke
				(width 0)
				(type default)
			)
			(fill yes)
			(layer "F.Paste")
		)
		(fp_poly
			(pts
				(xy 0.3302 -1.09601) (xy 2.5019 -1.09601) (xy 2.5019 -3.36931) (xy 0.3302 -3.36931)
			)
			(stroke
				(width 0)
				(type default)
			)
			(fill yes)
			(layer "F.Paste")
		)
		(fp_rect
			(start -2.4511 0.3048)
			(end 2.4511 -5.6896)
			(stroke
				(width 0)
				(type default)
			)
			(fill no)
			(layer "F.CrtYd")
		)
		(fp_poly
			(pts
				(xy -3.0099 1.3208) (xy -3.0099 -6.8072) (xy 3.0099 -6.8072) (xy 3.0099 -1.016) (xy 2.4511 -1.016)
				(xy 2.4511 -5.6896) (xy -2.4511 -5.6896) (xy -2.4511 0.3048) (xy 2.4511 0.3048) (xy 2.4511 -1.0033)
				(xy 3.0099 -1.0033) (xy 3.0099 1.3208)
			)
			(stroke
				(width 0)
				(type default)
			)
			(fill no)
			(layer "F.CrtYd")
		)
		(fp_rect
			(start -3.0099 1.3208)
			(end 3.0099 -6.8072)
			(stroke
				(width 0)
				(type default)
			)
			(fill no)
			(layer "F.Fab")
		)
		(pad "1" smd rect
			(at -1.905 0)
			(size 0.762 1.6256)
			(layers "F.Cu" "F.Mask" "F.Paste")
			(net "P12V")
		)
		(pad "2" smd rect
			(at -0.635 0)
			(size 0.762 1.6256)
			(layers "F.Cu" "F.Mask" "F.Paste")
			(net "P12V")
		)
		(pad "3" smd rect
			(at 0.635 0)
			(size 0.762 1.6256)
			(layers "F.Cu" "F.Mask" "F.Paste")
			(net "P12V")
		)
		(pad "4" smd rect
			(at 1.905 0)
			(size 0.762 1.6256)
			(layers "F.Cu" "F.Mask" "F.Paste")
			(net "ADM1276_GATE_DRV3")
		)
		(pad "5" smd rect
			(at 0 -3.69951)
			(size 5.0038 5.207)
			(layers "F.Cu" "F.Mask" "F.Paste")
			(net "P12V_SENSE_TRACE")
		)
	)
	(footprint ""
		(layer "F.Cu")
		(at 6.999986 -39.99992)
		(property "Reference" "H2"
			(at 0 0 0)
			(layer "F.SilkS")
			(hide yes)
			(effects
				(font
					(size 1.27 1.27)
				)
			)
		)
		(property "Value" "HOLE315R158"
			(at -5.08 -0.4572 0)
			(unlocked yes)
			(layer "F.Fab")
			(hide yes)
			(effects
				(font
					(size 1.016 1.016)
					(thickness 0.1524)
				)
			)
		)
		(property "Device Type" "HOLE315R158"
			(at -5.08 -1.9812 0)
			(unlocked yes)
			(layer "F.Fab")
			(hide yes)
			(effects
				(font
					(size 1.016 1.016)
					(thickness 0.1524)
				)
			)
		)
		(duplicate_pad_numbers_are_jumpers no)
		(fp_poly
			(pts
				(arc
					(start -4.3053 0)
					(mid 4.3053 0)
					(end -4.3053 0)
				)
			)
			(stroke
				(width 0)
				(type default)
			)
			(fill no)
			(layer "B.CrtYd")
		)
		(fp_poly
			(pts
				(arc
					(start -4.3053 0)
					(mid 4.3053 0)
					(end -4.3053 0)
				)
			)
			(stroke
				(width 0)
				(type default)
			)
			(fill no)
			(layer "F.CrtYd")
		)
		(fp_poly
			(pts
				(arc
					(start -4.3053 0)
					(mid 4.3053 0)
					(end -4.3053 0)
				)
			)
			(stroke
				(width 0)
				(type default)
			)
			(fill no)
			(layer "B.Fab")
		)
		(fp_poly
			(pts
				(arc
					(start -4.3053 0)
					(mid 4.3053 0)
					(end -4.3053 0)
				)
			)
			(stroke
				(width 0)
				(type default)
			)
			(fill no)
			(layer "F.Fab")
		)
		(pad "1" thru_hole circle
			(at 0 0)
			(size 8.001 8.001)
			(drill 4.0132)
			(layers "*.Cu" "*.Mask")
			(remove_unused_layers no)
			(net "GND")
			(clearance -1.4859)
			(thermal_gap 0.3048)
			(padstack
				(mode front_inner_back)
				(layer "Inner"
					(shape circle)
					(size 4.4196 4.4196)
					(clearance 0.3048)
				)
				(layer "B.Cu"
					(shape circle)
					(size 8.001 8.001)
					(clearance -1.4859)
				)
			)
		)
	)
	(footprint ""
		(layer "F.Cu")
		(at 23.622 -365.506 90)
		(property "Reference" "PR1"
			(at 0 0 90)
			(layer "F.SilkS")
			(hide yes)
			(effects
				(font
					(size 1.27 1.27)
				)
			)
		)
		(property "Value" "100KR2F-L1-GP"
			(at 0.064008 -3.993896 90)
			(unlocked yes)
			(layer "F.Fab")
			(hide yes)
			(effects
				(font
					(size 1.016 1.016)
					(thickness 0.1524)
				)
			)
		)
		(property "Device Type" "R402H16"
			(at 0.064008 -5.517896 90)
			(unlocked yes)
			(layer "F.Fab")
			(hide yes)
			(effects
				(font
					(size 1.016 1.016)
					(thickness 0.1524)
				)
			)
		)
		(duplicate_pad_numbers_are_jumpers no)
		(fp_line
			(start 0.508 -0.9398)
			(end -0.508 -0.9398)
			(stroke
				(width 0.1524)
				(type default)
			)
			(layer "F.SilkS")
		)
		(fp_line
			(start -0.508 -0.9398)
			(end -0.508 0.9398)
			(stroke
				(width 0.1524)
				(type default)
			)
			(layer "F.SilkS")
		)
		(fp_rect
			(start -0.508 0.9398)
			(end 0.508 -0.9398)
			(stroke
				(width 0)
				(type default)
			)
			(fill no)
			(layer "F.CrtYd")
		)
		(fp_rect
			(start -0.508 0.9398)
			(end 0.508 -0.9398)
			(stroke
				(width 0)
				(type default)
			)
			(fill no)
			(layer "F.Fab")
		)
		(pad "1" smd custom
			(at 0 -0.4445 90)
			(size 0.1397 0.1397)
			(layers "F.Cu" "F.Mask" "F.Paste")
			(net "ADM1276_VCAP")
			(options
				(clearance outline)
				(anchor circle)
			)
			(primitives
				(gr_poly
					(pts
						(arc
							(start -0.1778 -0.2794)
							(mid -0.249642 -0.249642)
							(end -0.2794 -0.1778)
						)
						(arc
							(start -0.2794 0.1778)
							(mid -0.249642 0.249642)
							(end -0.1778 0.2794)
						)
						(arc
							(start 0.1778 0.2794)
							(mid 0.249642 0.249642)
							(end 0.2794 0.1778)
						)
						(arc
							(start 0.2794 -0.1778)
							(mid 0.249642 -0.249642)
							(end 0.1778 -0.2794)
						)
					)
					(width 0)
					(fill yes)
				)
			)
		)
		(pad "2" smd custom
			(at 0 0.4445 90)
			(size 0.1397 0.1397)
			(layers "F.Cu" "F.Mask" "F.Paste")
			(net "ADM1276_ISET")
			(options
				(clearance outline)
				(anchor circle)
			)
			(primitives
				(gr_poly
					(pts
						(arc
							(start -0.1778 -0.2794)
							(mid -0.249642 -0.249642)
							(end -0.2794 -0.1778)
						)
						(arc
							(start -0.2794 0.1778)
							(mid -0.249642 0.249642)
							(end -0.1778 0.2794)
						)
						(arc
							(start 0.1778 0.2794)
							(mid 0.249642 0.249642)
							(end 0.2794 0.1778)
						)
						(arc
							(start 0.2794 -0.1778)
							(mid 0.249642 -0.249642)
							(end 0.1778 -0.2794)
						)
					)
					(width 0)
					(fill yes)
				)
			)
		)
	)
)
